(kicad_pcb
	(version 20260206)
	(generator "pcbnew")
	(generator_version "10.0")
	(general
		(thickness 1.6)
		(legacy_teardrops no)
	)
	(paper "A4")
	(title_block
		(title "04192023_DAF0TMB3IC0_F0TG_MB_C_brd_V02_OCP.brd")
		(comment 1 "Grand Teton / footprint 1669 of 8354 (U18), pads 210-319 of 484")
	)
	(layers
		(0 "F.Cu" signal "TOP")
		(4 "In1.Cu" signal "GND")
		(6 "In2.Cu" signal "IN1")
		(8 "In3.Cu" signal "GND1")
		(10 "In4.Cu" signal "IN2")
		(12 "In5.Cu" signal "GND2")
		(14 "In6.Cu" signal "IN3")
		(16 "In7.Cu" signal "GND3")
		(18 "In8.Cu" signal "VCC")
		(20 "In9.Cu" signal "VCC1")
		(22 "In10.Cu" signal "GND4")
		(24 "In11.Cu" signal "IN4")
		(26 "In12.Cu" signal "GND5")
		(28 "In13.Cu" signal "IN5")
		(30 "In14.Cu" signal "GND6")
		(32 "In15.Cu" signal "IN6")
		(34 "In16.Cu" signal "GND7")
		(2 "B.Cu" signal "BOTTOM")
		(9 "F.Adhes" user "F.Adhesive")
		(11 "B.Adhes" user "B.Adhesive")
		(13 "F.Paste" user "Package Geometry/Pastemask Top")
		(15 "B.Paste" user "Package Geometry/Pastemask Bottom")
		(5 "F.SilkS" user "Ref Des/Silkscreen Top")
		(7 "B.SilkS" user "Ref Des/Silkscreen Bottom")
		(1 "F.Mask" user "Board Geometry/Soldermask Top")
		(3 "B.Mask" user "Board Geometry/Soldermask Bottom")
		(17 "Dwgs.User" user "User.Drawings")
		(19 "Cmts.User" user "User.Comments")
		(21 "Eco1.User" user "User.Eco1")
		(23 "Eco2.User" user "User.Eco2")
		(25 "Edge.Cuts" user "Board Geometry/Outline")
		(27 "Margin" user)
		(31 "F.CrtYd" user "Package Geometry/Place Bound Top")
		(29 "B.CrtYd" user "Package Geometry/Place Bound Bottom")
		(35 "F.Fab" user "Ref Des/Assembly Top")
		(33 "B.Fab" user "Ref Des/Assembly Bottom")
	)
	(footprint ""
		(layer "F.Cu")
		(at 185.522108 -115.052856 90)
		(property "Reference" "U18"
			(at -10.68451 -12.951206 0)
			(unlocked yes)
			(layer "F.SilkS")
			(effects
				(font
					(size 0.7874 0.5842)
					(thickness 0.1524)
				)
				(justify left)
			)
		)
		(property "Value" ""
			(at 0 0 90)
			(layer "F.Fab")
			(effects
				(font
					(size 1.27 1.27)
				)
			)
		)
		(duplicate_pad_numbers_are_jumpers no)
		(pad "H12" smd circle
			(at 0.40005 -2.800096 90)
			(size 0.4064 0.4064)
			(layers "F.Cu" "F.Mask" "F.Paste")
			(net "P3V3_AUX")
		)
		(pad "H13" smd circle
			(at 1.199896 -2.800096 90)
			(size 0.4064 0.4064)
			(layers "F.Cu" "F.Mask" "F.Paste")
			(net "GND")
		)
		(pad "H14" smd circle
			(at 1.999996 -2.800096 90)
			(size 0.4064 0.4064)
			(layers "F.Cu" "F.Mask" "F.Paste")
			(net "P3V3_AUX")
		)
		(pad "H15" smd circle
			(at 2.800096 -2.800096 90)
			(size 0.4064 0.4064)
			(layers "F.Cu" "F.Mask" "F.Paste")
			(net "GND")
		)
		(pad "H16" smd circle
			(at 3.599942 -2.800096 90)
			(size 0.4064 0.4064)
			(layers "F.Cu" "F.Mask" "F.Paste")
			(net "PVDD11_S3_P1_RESET_N")
		)
		(pad "H17" smd circle
			(at 4.400042 -2.800096 90)
			(size 0.4064 0.4064)
			(layers "F.Cu" "F.Mask" "F.Paste")
			(net "PVDD11_S3_P0_RESET_N")
		)
		(pad "H18" smd circle
			(at 5.199888 -2.800096 90)
			(size 0.4064 0.4064)
			(layers "F.Cu" "F.Mask" "F.Paste")
			(net "FM_CPU1_NV_SAVE_N")
		)
		(pad "H19" smd circle
			(at 5.999988 -2.800096 90)
			(size 0.4064 0.4064)
			(layers "F.Cu" "F.Mask" "F.Paste")
			(net "FM_PWRGD_CPU0_PWROK")
		)
		(pad "H20" smd circle
			(at 6.800088 -2.800096 90)
			(size 0.4064 0.4064)
			(layers "F.Cu" "F.Mask" "F.Paste")
			(net "CPU0_JTAG_BUF_R_OE")
		)
		(pad "H21" smd circle
			(at 7.599934 -2.800096 90)
			(size 0.4064 0.4064)
			(layers "F.Cu" "F.Mask" "F.Paste")
			(net "FM_RST_CPU1_RESETL_N")
		)
		(pad "H22" smd circle
			(at 8.400034 -2.800096 90)
			(size 0.4064 0.4064)
			(layers "F.Cu" "F.Mask" "F.Paste")
			(net "FM_RST_CPU0_RESETL_N")
		)
		(pad "J1" smd circle
			(at -8.400034 -1.999996 90)
			(size 0.4064 0.4064)
			(layers "F.Cu" "F.Mask" "F.Paste")
			(net "FAB_BMC_REV_ID0")
		)
		(pad "J2" smd circle
			(at -7.599934 -1.999996 90)
			(size 0.4064 0.4064)
			(layers "F.Cu" "F.Mask" "F.Paste")
			(net "FM_CPU0_SA1")
		)
		(pad "J3" smd circle
			(at -6.800088 -1.999996 90)
			(size 0.4064 0.4064)
			(layers "F.Cu" "F.Mask" "F.Paste")
			(net "FM_INT_CPU0_HP_UBM_R_N")
		)
		(pad "J4" smd circle
			(at -5.999988 -1.999996 90)
			(size 0.4064 0.4064)
			(layers "F.Cu" "F.Mask" "F.Paste")
			(net "RT_BOARD_ID_ID0")
		)
		(pad "J5" smd circle
			(at -5.199888 -1.999996 90)
			(size 0.4064 0.4064)
			(layers "F.Cu" "F.Mask" "F.Paste")
			(net "CPU1_THERMTRIP_R_N")
		)
		(pad "J6" smd circle
			(at -4.400042 -1.999996 90)
			(size 0.4064 0.4064)
			(layers "F.Cu" "F.Mask" "F.Paste")
			(net "FM_CPU0_PROCHOT_R_N")
		)
		(pad "J7" smd circle
			(at -3.599942 -1.999996 90)
			(size 0.4064 0.4064)
			(layers "F.Cu" "F.Mask" "F.Paste")
			(net "FM_CPU1_SA0")
		)
		(pad "J8" smd circle
			(at -2.800096 -1.999996 90)
			(size 0.4064 0.4064)
			(layers "F.Cu" "F.Mask" "F.Paste")
			(net "P1V8_AUX")
		)
		(pad "J9" smd circle
			(at -1.999996 -1.999996 90)
			(size 0.4064 0.4064)
			(layers "F.Cu" "F.Mask" "F.Paste")
			(net "GND")
		)
		(pad "J10" smd circle
			(at -1.199896 -1.999996 90)
			(size 0.4064 0.4064)
			(layers "F.Cu" "F.Mask" "F.Paste")
			(net "GND")
		)
		(pad "J11" smd circle
			(at -0.40005 -1.999996 90)
			(size 0.4064 0.4064)
			(layers "F.Cu" "F.Mask" "F.Paste")
			(net "GND")
		)
		(pad "J12" smd circle
			(at 0.40005 -1.999996 90)
			(size 0.4064 0.4064)
			(layers "F.Cu" "F.Mask" "F.Paste")
			(net "GND")
		)
		(pad "J13" smd circle
			(at 1.199896 -1.999996 90)
			(size 0.4064 0.4064)
			(layers "F.Cu" "F.Mask" "F.Paste")
			(net "GND")
		)
		(pad "J14" smd circle
			(at 1.999996 -1.999996 90)
			(size 0.4064 0.4064)
			(layers "F.Cu" "F.Mask" "F.Paste")
			(net "GND")
		)
		(pad "J15" smd circle
			(at 2.800096 -1.999996 90)
			(size 0.4064 0.4064)
			(layers "F.Cu" "F.Mask" "F.Paste")
			(net "P1V8_AUX")
		)
		(pad "J16" smd circle
			(at 3.599942 -1.999996 90)
			(size 0.4064 0.4064)
			(layers "F.Cu" "F.Mask" "F.Paste")
			(net "FM_CPU0_NMI_SYNC_FLOOD_N")
		)
		(pad "J17" smd circle
			(at 4.400042 -1.999996 90)
			(size 0.4064 0.4064)
			(layers "F.Cu" "F.Mask" "F.Paste")
			(net "FM_FPGA_DEBUG_LED_CTRL")
		)
		(pad "J18" smd circle
			(at 5.199888 -1.999996 90)
			(size 0.4064 0.4064)
			(layers "F.Cu" "F.Mask" "F.Paste")
			(net "FM_PWRGD_CPU1_PWROK")
		)
		(pad "J19" smd circle
			(at 5.999988 -1.999996 90)
			(size 0.4064 0.4064)
			(layers "F.Cu" "F.Mask" "F.Paste")
			(net "FM_P1_PCC0_R_N")
		)
		(pad "J20" smd circle
			(at 6.800088 -1.999996 90)
			(size 0.4064 0.4064)
			(layers "F.Cu" "F.Mask" "F.Paste")
			(net "FM_P1_PCC1_R_N")
		)
		(pad "J21" smd circle
			(at 7.599934 -1.999996 90)
			(size 0.4064 0.4064)
			(layers "F.Cu" "F.Mask" "F.Paste")
			(net "TP_SLOT2_CLKREQ_0_R_N")
		)
		(pad "J22" smd circle
			(at 8.400034 -1.999996 90)
			(size 0.4064 0.4064)
			(layers "F.Cu" "F.Mask" "F.Paste")
			(net "FM_CPU0_PWR_BTN_N")
		)
		(pad "K1" smd circle
			(at -8.400034 -1.199896 90)
			(size 0.4064 0.4064)
			(layers "F.Cu" "F.Mask" "F.Paste")
			(net "FM_SEC_MUX_R_SEL")
		)
		(pad "K2" smd circle
			(at -7.599934 -1.199896 90)
			(size 0.4064 0.4064)
			(layers "F.Cu" "F.Mask" "F.Paste")
			(net "FM_SEC_MUX_OE_R_N")
		)
		(pad "K3" smd circle
			(at -6.800088 -1.199896 90)
			(size 0.4064 0.4064)
			(layers "F.Cu" "F.Mask" "F.Paste")
			(net "E1S_0_P3V3_P12V_ADC_ALERT")
		)
		(pad "K4" smd circle
			(at -5.999988 -1.199896 90)
			(size 0.4064 0.4064)
			(layers "F.Cu" "F.Mask" "F.Paste")
			(net "P12V_HSC_T_CRIT_R_N")
		)
		(pad "K5" smd circle
			(at -5.199888 -1.199896 90)
			(size 0.4064 0.4064)
			(layers "F.Cu" "F.Mask" "F.Paste")
			(net "P12V_SCM_ADC_ALERT")
		)
		(pad "K6" smd circle
			(at -4.400042 -1.199896 90)
			(size 0.4064 0.4064)
			(layers "F.Cu" "F.Mask" "F.Paste")
			(net "FAB_BMC_REV_ID2")
		)
		(pad "K7" smd circle
			(at -3.599942 -1.199896 90)
			(size 0.4064 0.4064)
			(layers "F.Cu" "F.Mask" "F.Paste")
			(net "FAB_BMC_REV_ID1")
		)
		(pad "K8" smd circle
			(at -2.800096 -1.199896 90)
			(size 0.4064 0.4064)
			(layers "F.Cu" "F.Mask" "F.Paste")
			(net "P1V8_AUX")
		)
		(pad "K9" smd circle
			(at -1.999996 -1.199896 90)
			(size 0.4064 0.4064)
			(layers "F.Cu" "F.Mask" "F.Paste")
			(net "GND")
		)
		(pad "K10" smd circle
			(at -1.199896 -1.199896 90)
			(size 0.4064 0.4064)
			(layers "F.Cu" "F.Mask" "F.Paste")
			(net "P3V3_AUX")
		)
		(pad "K11" smd circle
			(at -0.40005 -1.199896 90)
			(size 0.4064 0.4064)
			(layers "F.Cu" "F.Mask" "F.Paste")
			(net "P3V3_AUX")
		)
		(pad "K12" smd circle
			(at 0.40005 -1.199896 90)
			(size 0.4064 0.4064)
			(layers "F.Cu" "F.Mask" "F.Paste")
			(net "P3V3_AUX")
		)
		(pad "K13" smd circle
			(at 1.199896 -1.199896 90)
			(size 0.4064 0.4064)
			(layers "F.Cu" "F.Mask" "F.Paste")
			(net "P3V3_AUX")
		)
		(pad "K14" smd circle
			(at 1.999996 -1.199896 90)
			(size 0.4064 0.4064)
			(layers "F.Cu" "F.Mask" "F.Paste")
			(net "GND")
		)
		(pad "K15" smd circle
			(at 2.800096 -1.199896 90)
			(size 0.4064 0.4064)
			(layers "F.Cu" "F.Mask" "F.Paste")
			(net "P1V8_AUX")
		)
		(pad "K16" smd circle
			(at 3.599942 -1.199896 90)
			(size 0.4064 0.4064)
			(layers "F.Cu" "F.Mask" "F.Paste")
			(net "APML_CPU1_ALERT_R_N")
		)
		(pad "K17" smd circle
			(at 4.400042 -1.199896 90)
			(size 0.4064 0.4064)
			(layers "F.Cu" "F.Mask" "F.Paste")
			(net "FM_P0_PCC0_R_N")
		)
		(pad "K18" smd circle
			(at 5.199888 -1.199896 90)
			(size 0.4064 0.4064)
			(layers "F.Cu" "F.Mask" "F.Paste")
			(net "FM_P0_PCC1_R_N")
		)
		(pad "K19" smd circle
			(at 5.999988 -1.199896 90)
			(size 0.4064 0.4064)
			(layers "F.Cu" "F.Mask" "F.Paste")
			(net "RST_RT_CPU1_P2_RESET_R2_N")
		)
		(pad "K20" smd circle
			(at 6.800088 -1.199896 90)
			(size 0.4064 0.4064)
			(layers "F.Cu" "F.Mask" "F.Paste")
			(net "RST_RT_CPU1_P2_PERST_R2_N")
		)
		(pad "K21" smd circle
			(at 7.599934 -1.199896 90)
			(size 0.4064 0.4064)
			(layers "F.Cu" "F.Mask" "F.Paste")
			(net "GND")
		)
		(pad "K22" smd circle
			(at 8.400034 -1.199896 90)
			(size 0.4064 0.4064)
			(layers "F.Cu" "F.Mask" "F.Paste")
			(net "RST_RT_CPU0_P0_PERST_R2_N")
		)
		(pad "L1" smd circle
			(at -8.400034 -0.40005 90)
			(size 0.4064 0.4064)
			(layers "F.Cu" "F.Mask" "F.Paste")
			(net "LED_HDD_ACTIVITY_B_PLD_N")
		)
		(pad "L2" smd circle
			(at -7.599934 -0.40005 90)
			(size 0.4064 0.4064)
			(layers "F.Cu" "F.Mask" "F.Paste")
			(net "GND")
		)
		(pad "L3" smd circle
			(at -6.800088 -0.40005 90)
			(size 0.4064 0.4064)
			(layers "F.Cu" "F.Mask" "F.Paste")
			(net "FM_THERMAL_ALERT_R_N")
		)
		(pad "L4" smd circle
			(at -5.999988 -0.40005 90)
			(size 0.4064 0.4064)
			(layers "F.Cu" "F.Mask" "F.Paste")
			(net "SMB_BMC_GPU_EN")
		)
		(pad "L5" smd circle
			(at -5.199888 -0.40005 90)
			(size 0.4064 0.4064)
			(layers "F.Cu" "F.Mask" "F.Paste")
			(net "PVDDCR_CPU1_P0_SMB_ALERT")
		)
		(pad "L6" smd circle
			(at -4.400042 -0.40005 90)
			(size 0.4064 0.4064)
			(layers "F.Cu" "F.Mask" "F.Paste")
			(net "PVDDCR_CPU1_P1_SMB_ALERT")
		)
		(pad "L7" smd circle
			(at -3.599942 -0.40005 90)
			(size 0.4064 0.4064)
			(layers "F.Cu" "F.Mask" "F.Paste")
			(net "PVDD11_S3_P0_PMALERT")
		)
		(pad "L8" smd circle
			(at -2.800096 -0.40005 90)
			(size 0.4064 0.4064)
			(layers "F.Cu" "F.Mask" "F.Paste")
			(net "P3V3_AUX")
		)
		(pad "L9" smd circle
			(at -1.999996 -0.40005 90)
			(size 0.4064 0.4064)
			(layers "F.Cu" "F.Mask" "F.Paste")
			(net "GND")
		)
		(pad "L10" smd circle
			(at -1.199896 -0.40005 90)
			(size 0.4064 0.4064)
			(layers "F.Cu" "F.Mask" "F.Paste")
			(net "GND")
		)
		(pad "L11" smd circle
			(at -0.40005 -0.40005 90)
			(size 0.4064 0.4064)
			(layers "F.Cu" "F.Mask" "F.Paste")
			(net "P3V3_AUX")
		)
		(pad "L12" smd circle
			(at 0.40005 -0.40005 90)
			(size 0.4064 0.4064)
			(layers "F.Cu" "F.Mask" "F.Paste")
			(net "P3V3_AUX")
		)
		(pad "L13" smd circle
			(at 1.199896 -0.40005 90)
			(size 0.4064 0.4064)
			(layers "F.Cu" "F.Mask" "F.Paste")
			(net "GND")
		)
		(pad "L14" smd circle
			(at 1.999996 -0.40005 90)
			(size 0.4064 0.4064)
			(layers "F.Cu" "F.Mask" "F.Paste")
			(net "GND")
		)
		(pad "L15" smd circle
			(at 2.800096 -0.40005 90)
			(size 0.4064 0.4064)
			(layers "F.Cu" "F.Mask" "F.Paste")
			(net "P1V8_AUX")
		)
		(pad "L16" smd circle
			(at 3.599942 -0.40005 90)
			(size 0.4064 0.4064)
			(layers "F.Cu" "F.Mask" "F.Paste")
			(net "CPU1_SPD_HOST_CTRL_R1_N")
		)
		(pad "L17" smd circle
			(at 4.400042 -0.40005 90)
			(size 0.4064 0.4064)
			(layers "F.Cu" "F.Mask" "F.Paste")
			(net "APML_CPU0_ALERT_R_N")
		)
		(pad "L18" smd circle
			(at 5.199888 -0.40005 90)
			(size 0.4064 0.4064)
			(layers "F.Cu" "F.Mask" "F.Paste")
			(net "GND")
		)
		(pad "L19" smd circle
			(at 5.999988 -0.40005 90)
			(size 0.4064 0.4064)
			(layers "F.Cu" "F.Mask" "F.Paste")
			(net "RST_RT_CPU1_P3_PERST_R2_N")
		)
		(pad "L20" smd circle
			(at 6.800088 -0.40005 90)
			(size 0.4064 0.4064)
			(layers "F.Cu" "F.Mask" "F.Paste")
			(net "RST_RT_CPU1_P3_RESET_R2_N")
		)
		(pad "L21" smd circle
			(at 7.599934 -0.40005 90)
			(size 0.4064 0.4064)
			(layers "F.Cu" "F.Mask" "F.Paste")
			(net "RST_RT_CPU0_P0_RESET_R2_N")
		)
		(pad "L22" smd circle
			(at 8.400034 -0.40005 90)
			(size 0.4064 0.4064)
			(layers "F.Cu" "F.Mask" "F.Paste")
			(net "RST_RT_CPU0_P1_PERST_R2_N")
		)
		(pad "M1" smd circle
			(at -8.400034 0.40005 90)
			(size 0.4064 0.4064)
			(layers "F.Cu" "F.Mask" "F.Paste")
			(net "M2_0_P3V3_ADC_ALERT")
		)
		(pad "M2" smd circle
			(at -7.599934 0.40005 90)
			(size 0.4064 0.4064)
			(layers "F.Cu" "F.Mask" "F.Paste")
			(net "FM_SCM_PRSNT1_N")
		)
		(pad "M3" smd circle
			(at -6.800088 0.40005 90)
			(size 0.4064 0.4064)
			(layers "F.Cu" "F.Mask" "F.Paste")
			(net "P3V3_AUX")
		)
		(pad "M4" smd circle
			(at -5.999988 0.40005 90)
			(size 0.4064 0.4064)
			(layers "F.Cu" "F.Mask" "F.Paste")
			(net "GND")
		)
		(pad "M5" smd circle
			(at -5.199888 0.40005 90)
			(size 0.4064 0.4064)
			(layers "F.Cu" "F.Mask" "F.Paste")
			(net "PVDDCR_CPU0_P1_PMALERT")
		)
		(pad "M6" smd circle
			(at -4.400042 0.40005 90)
			(size 0.4064 0.4064)
			(layers "F.Cu" "F.Mask" "F.Paste")
			(net "FM_PLD_OCP_SFF_AUX_PWR_R_EN")
		)
		(pad "M7" smd circle
			(at -3.599942 0.40005 90)
			(size 0.4064 0.4064)
			(layers "F.Cu" "F.Mask" "F.Paste")
			(net "FM_PLD_OCP_SFF_MAIN_PWR_EN_R")
		)
		(pad "M8" smd circle
			(at -2.800096 0.40005 90)
			(size 0.4064 0.4064)
			(layers "F.Cu" "F.Mask" "F.Paste")
			(net "P3V3_AUX")
		)
		(pad "M9" smd circle
			(at -1.999996 0.40005 90)
			(size 0.4064 0.4064)
			(layers "F.Cu" "F.Mask" "F.Paste")
			(net "GND")
		)
		(pad "M10" smd circle
			(at -1.199896 0.40005 90)
			(size 0.4064 0.4064)
			(layers "F.Cu" "F.Mask" "F.Paste")
			(net "GND")
		)
		(pad "M11" smd circle
			(at -0.40005 0.40005 90)
			(size 0.4064 0.4064)
			(layers "F.Cu" "F.Mask" "F.Paste")
			(net "P3V3_AUX")
		)
		(pad "M12" smd circle
			(at 0.40005 0.40005 90)
			(size 0.4064 0.4064)
			(layers "F.Cu" "F.Mask" "F.Paste")
			(net "P3V3_AUX")
		)
		(pad "M13" smd circle
			(at 1.199896 0.40005 90)
			(size 0.4064 0.4064)
			(layers "F.Cu" "F.Mask" "F.Paste")
			(net "GND")
		)
		(pad "M14" smd circle
			(at 1.999996 0.40005 90)
			(size 0.4064 0.4064)
			(layers "F.Cu" "F.Mask" "F.Paste")
			(net "GND")
		)
		(pad "M15" smd circle
			(at 2.800096 0.40005 90)
			(size 0.4064 0.4064)
			(layers "F.Cu" "F.Mask" "F.Paste")
			(net "P1V8_AUX")
		)
		(pad "M16" smd circle
			(at 3.599942 0.40005 90)
			(size 0.4064 0.4064)
			(layers "F.Cu" "F.Mask" "F.Paste")
			(net "PWRGD_P3V3_R2")
		)
		(pad "M17" smd circle
			(at 4.400042 0.40005 90)
			(size 0.4064 0.4064)
			(layers "F.Cu" "F.Mask" "F.Paste")
			(net "RST_RT_CPU0_P1_RESET_R2_N")
		)
		(pad "M18" smd circle
			(at 5.199888 0.40005 90)
			(size 0.4064 0.4064)
			(layers "F.Cu" "F.Mask" "F.Paste")
			(net "P1V8_AUX")
		)
		(pad "M19" smd circle
			(at 5.999988 0.40005 90)
			(size 0.4064 0.4064)
			(layers "F.Cu" "F.Mask" "F.Paste")
			(net "SMB_CPU_5_R1_SDA")
		)
		(pad "M20" smd circle
			(at 6.800088 0.40005 90)
			(size 0.4064 0.4064)
			(layers "F.Cu" "F.Mask" "F.Paste")
			(net "SMB_CPU_5_R1_SCL")
		)
		(pad "M21" smd circle
			(at 7.599934 0.40005 90)
			(size 0.4064 0.4064)
			(layers "F.Cu" "F.Mask" "F.Paste")
			(net "FM_CPU0_SMERR_N")
		)
		(pad "M22" smd circle
			(at 8.400034 0.40005 90)
			(size 0.4064 0.4064)
			(layers "F.Cu" "F.Mask" "F.Paste")
			(net "FM_SMERR_LED_R_N")
		)
		(pad "N1" smd circle
			(at -8.400034 1.199896 90)
			(size 0.4064 0.4064)
			(layers "F.Cu" "F.Mask" "F.Paste")
			(net "PVDD11_S3_P1_PMALERT")
		)
		(pad "N2" smd circle
			(at -7.599934 1.199896 90)
			(size 0.4064 0.4064)
			(layers "F.Cu" "F.Mask" "F.Paste")
			(net "FM_CLKREQ_M2_1_N")
		)
		(pad "N3" smd circle
			(at -6.800088 1.199896 90)
			(size 0.4064 0.4064)
			(layers "F.Cu" "F.Mask" "F.Paste")
			(net "FM_CLR_CMOS")
		)
		(pad "N4" smd circle
			(at -5.999988 1.199896 90)
			(size 0.4064 0.4064)
			(layers "F.Cu" "F.Mask" "F.Paste")
			(net "PWRGD_OCP_SFF_PWR_GOOD")
		)
		(pad "N5" smd circle
			(at -5.199888 1.199896 90)
			(size 0.4064 0.4064)
			(layers "F.Cu" "F.Mask" "F.Paste")
			(net "FM_CPU0_SP5R1")
		)
		(pad "N6" smd circle
			(at -4.400042 1.199896 90)
			(size 0.4064 0.4064)
			(layers "F.Cu" "F.Mask" "F.Paste")
			(net "FM_CPU0_SP5R2")
		)
		(pad "N7" smd circle
			(at -3.599942 1.199896 90)
			(size 0.4064 0.4064)
			(layers "F.Cu" "F.Mask" "F.Paste")
			(net "P12V_HSC_TEMP_ALERT_R_N")
		)
		(pad "N8" smd circle
			(at -2.800096 1.199896 90)
			(size 0.4064 0.4064)
			(layers "F.Cu" "F.Mask" "F.Paste")
			(net "P3V3_AUX")
		)
		(pad "N9" smd circle
			(at -1.999996 1.199896 90)
			(size 0.4064 0.4064)
			(layers "F.Cu" "F.Mask" "F.Paste")
			(net "GND")
		)
		(pad "N10" smd circle
			(at -1.199896 1.199896 90)
			(size 0.4064 0.4064)
			(layers "F.Cu" "F.Mask" "F.Paste")
			(net "P3V3_AUX")
		)
		(pad "N11" smd circle
			(at -0.40005 1.199896 90)
			(size 0.4064 0.4064)
			(layers "F.Cu" "F.Mask" "F.Paste")
			(net "P3V3_AUX")
		)
	)
)
